(kicad_pcb
	(version 20260206)
	(generator "pcbnew")
	(generator_version "10.0")
	(general
		(thickness 1.6)
		(legacy_teardrops no)
	)
	(paper "A4")
	(title_block
		(title "01162023_DA0F0TEBIF0_F0T_Expander_BD_F_brd_V02_OCP.brd")
		(comment 1 "Grand Teton / footprints 4641-4647 of 9728")
	)
	(layers
		(0 "F.Cu" signal "TOP")
		(4 "In1.Cu" signal "GND")
		(6 "In2.Cu" signal "VCC")
		(8 "In3.Cu" signal "VCC1")
		(10 "In4.Cu" signal "GND1")
		(12 "In5.Cu" signal "IN1")
		(14 "In6.Cu" signal "GND2")
		(16 "In7.Cu" signal "IN2")
		(18 "In8.Cu" signal "GND3")
		(20 "In9.Cu" signal "IN3")
		(22 "In10.Cu" signal "GND4")
		(24 "In11.Cu" signal "IN4")
		(26 "In12.Cu" signal "GND5")
		(28 "In13.Cu" signal "IN5")
		(30 "In14.Cu" signal "GND6")
		(32 "In15.Cu" signal "IN6")
		(34 "In16.Cu" signal "GND7")
		(2 "B.Cu" signal "BOTTOM")
		(9 "F.Adhes" user "F.Adhesive")
		(11 "B.Adhes" user "B.Adhesive")
		(13 "F.Paste" user "Package Geometry/Pastemask Top")
		(15 "B.Paste" user "Package Geometry/Pastemask Bottom")
		(5 "F.SilkS" user "Ref Des/Silkscreen Top")
		(7 "B.SilkS" user "Ref Des/Silkscreen Bottom")
		(1 "F.Mask" user "Board Geometry/Soldermask Top")
		(3 "B.Mask" user "Board Geometry/Soldermask Bottom")
		(17 "Dwgs.User" user "User.Drawings")
		(19 "Cmts.User" user "User.Comments")
		(21 "Eco1.User" user "User.Eco1")
		(23 "Eco2.User" user "User.Eco2")
		(25 "Edge.Cuts" user "Board Geometry/Outline")
		(27 "Margin" user)
		(31 "F.CrtYd" user "Package Geometry/Place Bound Top")
		(29 "B.CrtYd" user "Package Geometry/Place Bound Bottom")
		(35 "F.Fab" user "Ref Des/Assembly Top")
		(33 "B.Fab" user "Ref Des/Assembly Bottom")
	)
	(footprint ""
		(layer "F.Cu")
		(at 14.653768 -162.003994 -90)
		(property "Reference" "R905"
			(at 0 0 270)
			(layer "F.SilkS")
			(hide yes)
			(effects
				(font
					(size 1.27 1.27)
				)
			)
		)
		(property "Value" ""
			(at 0 0 270)
			(layer "F.Fab")
			(effects
				(font
					(size 1.27 1.27)
				)
			)
		)
		(duplicate_pad_numbers_are_jumpers no)
		(fp_line
			(start -0.7874 0.4064)
			(end -0.7874 -0.4064)
			(stroke
				(width 0.1524)
				(type default)
			)
			(layer "F.SilkS")
		)
		(fp_line
			(start 0.7874 0.4064)
			(end -0.7874 0.4064)
			(stroke
				(width 0.1524)
				(type default)
			)
			(layer "F.SilkS")
		)
		(fp_line
			(start -0.7874 -0.4064)
			(end 0.7874 -0.4064)
			(stroke
				(width 0.1524)
				(type default)
			)
			(layer "F.SilkS")
		)
		(fp_line
			(start 0.7874 -0.4064)
			(end 0.7874 0.4064)
			(stroke
				(width 0.1524)
				(type default)
			)
			(layer "F.SilkS")
		)
		(fp_line
			(start -0.67945 0.3048)
			(end -0.67945 -0.305054)
			(stroke
				(width 0.1)
				(type default)
			)
			(layer "F.Fab")
		)
		(fp_line
			(start -0.12065 0.3048)
			(end -0.67945 0.3048)
			(stroke
				(width 0.1)
				(type default)
			)
			(layer "F.Fab")
		)
		(fp_line
			(start 0.120396 0.3048)
			(end 0.120396 0.2794)
			(stroke
				(width 0.1)
				(type default)
			)
			(layer "F.Fab")
		)
		(fp_line
			(start 0.67945 0.3048)
			(end 0.120396 0.3048)
			(stroke
				(width 0.1)
				(type default)
			)
			(layer "F.Fab")
		)
		(fp_line
			(start -0.12065 0.2794)
			(end -0.12065 0.3048)
			(stroke
				(width 0.1)
				(type default)
			)
			(layer "F.Fab")
		)
		(fp_line
			(start 0.120396 0.2794)
			(end -0.12065 0.2794)
			(stroke
				(width 0.1)
				(type default)
			)
			(layer "F.Fab")
		)
		(fp_line
			(start -0.12065 -0.2794)
			(end 0.12065 -0.2794)
			(stroke
				(width 0.1)
				(type default)
			)
			(layer "F.Fab")
		)
		(fp_line
			(start 0.12065 -0.2794)
			(end 0.12065 -0.3048)
			(stroke
				(width 0.1)
				(type default)
			)
			(layer "F.Fab")
		)
		(fp_line
			(start 0.12065 -0.3048)
			(end 0.67945 -0.3048)
			(stroke
				(width 0.1)
				(type default)
			)
			(layer "F.Fab")
		)
		(fp_line
			(start 0.67945 -0.3048)
			(end 0.67945 0.3048)
			(stroke
				(width 0.1)
				(type default)
			)
			(layer "F.Fab")
		)
		(fp_line
			(start -0.67945 -0.305054)
			(end -0.12065 -0.305054)
			(stroke
				(width 0.1)
				(type default)
			)
			(layer "F.Fab")
		)
		(fp_line
			(start -0.12065 -0.305054)
			(end -0.12065 -0.2794)
			(stroke
				(width 0.1)
				(type default)
			)
			(layer "F.Fab")
		)
		(pad "1" smd circle
			(at -0.40005 0 270)
			(size 0 0)
			(layers "F.Cu" "F.Mask" "F.Paste")
			(net "GND")
		)
		(pad "2" smd circle
			(at 0.40005 0 270)
			(size 0 0)
			(layers "F.Cu" "F.Mask" "F.Paste")
			(net "P12V_NIC0_CO_EN")
		)
	)
	(footprint ""
		(layer "F.Cu")
		(at 459.710282 -30.681168)
		(property "Reference" "H44"
			(at -3.729482 -2.540762 0)
			(unlocked yes)
			(layer "F.SilkS")
			(effects
				(font
					(size 0.7874 0.5842)
					(thickness 0.1524)
				)
				(justify left)
			)
		)
		(property "Value" ""
			(at 0 0 0)
			(layer "F.Fab")
			(effects
				(font
					(size 1.27 1.27)
				)
			)
		)
		(duplicate_pad_numbers_are_jumpers no)
		(fp_circle
			(center 0 0)
			(end 2.4003 0)
			(stroke
				(width 0.1524)
				(type default)
			)
			(fill no)
			(layer "F.SilkS")
		)
		(fp_circle
			(center 0 0)
			(end 6.5913 0)
			(stroke
				(width 0.1524)
				(type default)
			)
			(fill no)
			(layer "B.SilkS")
		)
		(fp_circle
			(center 0 0)
			(end 6.5913 0)
			(stroke
				(width 0.1)
				(type default)
			)
			(fill no)
			(layer "B.Fab")
		)
		(fp_circle
			(center 0 0)
			(end 2.4003 0)
			(stroke
				(width 0.1)
				(type default)
			)
			(fill no)
			(layer "F.Fab")
		)
		(pad "" np_thru_hole circle
			(at 0 0)
			(size 3.175 3.175)
			(drill 3.175)
			(layers "*.Cu" "*.Mask")
			(clearance 0.381)
			(thermal_gap 0.381)
		)
		(zone
			(layers "F.Cu" "B.Cu" "In1.Cu" "In2.Cu" "In3.Cu" "In4.Cu" "In5.Cu" "In6.Cu"
				"In7.Cu" "In8.Cu" "In9.Cu" "In10.Cu" "In11.Cu" "In12.Cu" "In13.Cu" "In14.Cu"
				"In15.Cu" "In16.Cu"
			)
			(hatch none 0.5)
			(connect_pads
				(clearance 0)
			)
			(min_thickness 0.25)
			(keepout
				(tracks not_allowed)
				(vias allowed)
				(pads allowed)
				(copperpour not_allowed)
				(footprints allowed)
			)
			(placement
				(enabled no)
				(sheetname "")
			)
			(fill
				(thermal_gap 0.5)
				(thermal_bridge_width 0.5)
				(island_removal_mode 0)
			)
			(polygon
				(pts
					(arc
						(start 461.805782 -30.681168)
						(mid 457.614782 -30.681168)
						(end 461.805782 -30.681168)
					)
				)
			)
		)
	)
	(footprint ""
		(layer "F.Cu")
		(at 203.040234 -143.182848 90)
		(property "Reference" "C4001"
			(at 0 0 90)
			(layer "F.SilkS")
			(hide yes)
			(effects
				(font
					(size 1.27 1.27)
				)
			)
		)
		(property "Value" ""
			(at 0 0 90)
			(layer "F.Fab")
			(effects
				(font
					(size 1.27 1.27)
				)
			)
		)
		(duplicate_pad_numbers_are_jumpers no)
		(fp_line
			(start 0.7874 -0.4064)
			(end 0.7874 0.4064)
			(stroke
				(width 0.1524)
				(type default)
			)
			(layer "F.SilkS")
		)
		(fp_line
			(start -0.7874 -0.4064)
			(end 0.7874 -0.4064)
			(stroke
				(width 0.1524)
				(type default)
			)
			(layer "F.SilkS")
		)
		(fp_line
			(start 0.7874 0.4064)
			(end -0.7874 0.4064)
			(stroke
				(width 0.1524)
				(type default)
			)
			(layer "F.SilkS")
		)
		(fp_line
			(start -0.7874 0.4064)
			(end -0.7874 -0.4064)
			(stroke
				(width 0.1524)
				(type default)
			)
			(layer "F.SilkS")
		)
		(fp_line
			(start -0.12065 -0.305054)
			(end -0.12065 -0.2794)
			(stroke
				(width 0.1)
				(type default)
			)
			(layer "F.Fab")
		)
		(fp_line
			(start -0.67945 -0.305054)
			(end -0.12065 -0.305054)
			(stroke
				(width 0.1)
				(type default)
			)
			(layer "F.Fab")
		)
		(fp_line
			(start 0.67945 -0.3048)
			(end 0.67945 0.3048)
			(stroke
				(width 0.1)
				(type default)
			)
			(layer "F.Fab")
		)
		(fp_line
			(start 0.12065 -0.3048)
			(end 0.67945 -0.3048)
			(stroke
				(width 0.1)
				(type default)
			)
			(layer "F.Fab")
		)
		(fp_line
			(start 0.12065 -0.2794)
			(end 0.12065 -0.3048)
			(stroke
				(width 0.1)
				(type default)
			)
			(layer "F.Fab")
		)
		(fp_line
			(start -0.12065 -0.2794)
			(end 0.12065 -0.2794)
			(stroke
				(width 0.1)
				(type default)
			)
			(layer "F.Fab")
		)
		(fp_line
			(start 0.120396 0.2794)
			(end -0.12065 0.2794)
			(stroke
				(width 0.1)
				(type default)
			)
			(layer "F.Fab")
		)
		(fp_line
			(start -0.12065 0.2794)
			(end -0.12065 0.3048)
			(stroke
				(width 0.1)
				(type default)
			)
			(layer "F.Fab")
		)
		(fp_line
			(start 0.67945 0.3048)
			(end 0.120396 0.3048)
			(stroke
				(width 0.1)
				(type default)
			)
			(layer "F.Fab")
		)
		(fp_line
			(start 0.120396 0.3048)
			(end 0.120396 0.2794)
			(stroke
				(width 0.1)
				(type default)
			)
			(layer "F.Fab")
		)
		(fp_line
			(start -0.12065 0.3048)
			(end -0.67945 0.3048)
			(stroke
				(width 0.1)
				(type default)
			)
			(layer "F.Fab")
		)
		(fp_line
			(start -0.67945 0.3048)
			(end -0.67945 -0.305054)
			(stroke
				(width 0.1)
				(type default)
			)
			(layer "F.Fab")
		)
		(pad "1" smd circle
			(at -0.40005 0 90)
			(size 0 0)
			(layers "F.Cu" "F.Mask" "F.Paste")
			(net "PRSNT_NIC3_R_N")
		)
		(pad "2" smd circle
			(at 0.40005 0 90)
			(size 0 0)
			(layers "F.Cu" "F.Mask" "F.Paste")
			(net "GND")
		)
	)
	(footprint ""
		(layer "F.Cu")
		(at 255.856486 -20.467574 180)
		(property "Reference" "R1689"
			(at 0 0 180)
			(layer "F.SilkS")
			(hide yes)
			(effects
				(font
					(size 1.27 1.27)
				)
			)
		)
		(property "Value" ""
			(at 0 0 180)
			(layer "F.Fab")
			(effects
				(font
					(size 1.27 1.27)
				)
			)
		)
		(duplicate_pad_numbers_are_jumpers no)
		(fp_line
			(start 0.7874 0.4064)
			(end -0.7874 0.4064)
			(stroke
				(width 0.1524)
				(type default)
			)
			(layer "F.SilkS")
		)
		(fp_line
			(start 0.7874 -0.4064)
			(end 0.7874 0.4064)
			(stroke
				(width 0.1524)
				(type default)
			)
			(layer "F.SilkS")
		)
		(fp_line
			(start -0.7874 0.4064)
			(end -0.7874 -0.4064)
			(stroke
				(width 0.1524)
				(type default)
			)
			(layer "F.SilkS")
		)
		(fp_line
			(start -0.7874 -0.4064)
			(end 0.7874 -0.4064)
			(stroke
				(width 0.1524)
				(type default)
			)
			(layer "F.SilkS")
		)
		(fp_line
			(start 0.67945 0.3048)
			(end 0.120396 0.3048)
			(stroke
				(width 0.1)
				(type default)
			)
			(layer "F.Fab")
		)
		(fp_line
			(start 0.67945 -0.3048)
			(end 0.67945 0.3048)
			(stroke
				(width 0.1)
				(type default)
			)
			(layer "F.Fab")
		)
		(fp_line
			(start 0.12065 -0.2794)
			(end 0.12065 -0.3048)
			(stroke
				(width 0.1)
				(type default)
			)
			(layer "F.Fab")
		)
		(fp_line
			(start 0.12065 -0.3048)
			(end 0.67945 -0.3048)
			(stroke
				(width 0.1)
				(type default)
			)
			(layer "F.Fab")
		)
		(fp_line
			(start 0.120396 0.3048)
			(end 0.120396 0.2794)
			(stroke
				(width 0.1)
				(type default)
			)
			(layer "F.Fab")
		)
		(fp_line
			(start 0.120396 0.2794)
			(end -0.12065 0.2794)
			(stroke
				(width 0.1)
				(type default)
			)
			(layer "F.Fab")
		)
		(fp_line
			(start -0.12065 0.3048)
			(end -0.67945 0.3048)
			(stroke
				(width 0.1)
				(type default)
			)
			(layer "F.Fab")
		)
		(fp_line
			(start -0.12065 0.2794)
			(end -0.12065 0.3048)
			(stroke
				(width 0.1)
				(type default)
			)
			(layer "F.Fab")
		)
		(fp_line
			(start -0.12065 -0.2794)
			(end 0.12065 -0.2794)
			(stroke
				(width 0.1)
				(type default)
			)
			(layer "F.Fab")
		)
		(fp_line
			(start -0.12065 -0.305054)
			(end -0.12065 -0.2794)
			(stroke
				(width 0.1)
				(type default)
			)
			(layer "F.Fab")
		)
		(fp_line
			(start -0.67945 0.3048)
			(end -0.67945 -0.305054)
			(stroke
				(width 0.1)
				(type default)
			)
			(layer "F.Fab")
		)
		(fp_line
			(start -0.67945 -0.305054)
			(end -0.12065 -0.305054)
			(stroke
				(width 0.1)
				(type default)
			)
			(layer "F.Fab")
		)
		(pad "1" smd circle
			(at -0.40005 0 180)
			(size 0 0)
			(layers "F.Cu" "F.Mask" "F.Paste")
			(net "P3V3_SSD8")
		)
		(pad "2" smd circle
			(at 0.40005 0 180)
			(size 0 0)
			(layers "F.Cu" "F.Mask" "F.Paste")
			(net "SMB_ISO_SSD8_SDA")
		)
	)
	(footprint ""
		(layer "F.Cu")
		(at 152.738328 -134.008876)
		(property "Reference" "C246"
			(at 0 0 0)
			(layer "F.SilkS")
			(hide yes)
			(effects
				(font
					(size 1.27 1.27)
				)
			)
		)
		(property "Value" ""
			(at 0 0 0)
			(layer "F.Fab")
			(effects
				(font
					(size 1.27 1.27)
				)
			)
		)
		(duplicate_pad_numbers_are_jumpers no)
		(fp_line
			(start -0.299974 -0.150114)
			(end 0.299974 -0.150114)
			(stroke
				(width 0.1)
				(type default)
			)
			(layer "F.Fab")
		)
		(fp_line
			(start -0.299974 0.150114)
			(end -0.299974 -0.150114)
			(stroke
				(width 0.1)
				(type default)
			)
			(layer "F.Fab")
		)
		(fp_line
			(start 0.299974 -0.150114)
			(end 0.299974 0.150114)
			(stroke
				(width 0.1)
				(type default)
			)
			(layer "F.Fab")
		)
		(fp_line
			(start 0.299974 0.150114)
			(end -0.299974 0.150114)
			(stroke
				(width 0.1)
				(type default)
			)
			(layer "F.Fab")
		)
		(pad "1" smd rect
			(at -0.2667 0)
			(size 0.3048 0.381)
			(layers "F.Cu" "F.Mask" "F.Paste")
			(net "P5E_PEX1_STN1_TX_DP<30>")
		)
		(pad "2" smd rect
			(at 0.2667 0)
			(size 0.3048 0.381)
			(layers "F.Cu" "F.Mask" "F.Paste")
			(net "P5E_PEX1_STN1_TX_C_DP<30>")
		)
	)
	(footprint ""
		(layer "F.Cu")
		(at 331.22362 -106.413808 180)
		(property "Reference" "PD11"
			(at 4.12242 2.144522 0)
			(unlocked yes)
			(layer "F.SilkS")
			(effects
				(font
					(size 0.7874 0.5842)
					(thickness 0.1524)
				)
				(justify left)
			)
		)
		(property "Value" ""
			(at 0 0 180)
			(layer "F.Fab")
			(effects
				(font
					(size 1.27 1.27)
				)
			)
		)
		(duplicate_pad_numbers_are_jumpers no)
		(fp_line
			(start 4.107942 1.459992)
			(end -3.400044 1.459992)
			(stroke
				(width 0.1524)
				(type default)
			)
			(layer "F.SilkS")
		)
		(fp_line
			(start 4.107942 -1.459992)
			(end 4.107942 1.459992)
			(stroke
				(width 0.1524)
				(type default)
			)
			(layer "F.SilkS")
		)
		(fp_line
			(start -3.400044 1.459992)
			(end -3.400044 -1.459992)
			(stroke
				(width 0.1524)
				(type default)
			)
			(layer "F.SilkS")
		)
		(fp_line
			(start -3.400044 -1.459992)
			(end 4.107942 -1.459992)
			(stroke
				(width 0.1524)
				(type default)
			)
			(layer "F.SilkS")
		)
		(fp_rect
			(start 4.107942 -1.459992)
			(end 3.308096 1.459992)
			(stroke
				(width 0)
				(type default)
			)
			(fill yes)
			(layer "F.SilkS")
		)
		(fp_line
			(start 2.29997 1.459992)
			(end -2.29997 1.459992)
			(stroke
				(width 0.1)
				(type default)
			)
			(layer "F.Fab")
		)
		(fp_line
			(start 2.29997 -1.459992)
			(end 2.29997 1.459992)
			(stroke
				(width 0.1)
				(type default)
			)
			(layer "F.Fab")
		)
		(fp_line
			(start -2.29997 1.459992)
			(end -2.29997 -1.459992)
			(stroke
				(width 0.1)
				(type default)
			)
			(layer "F.Fab")
		)
		(fp_line
			(start -2.29997 -1.459992)
			(end 2.29997 -1.459992)
			(stroke
				(width 0.1)
				(type default)
			)
			(layer "F.Fab")
		)
		(fp_text user "-"
			(at 4.946904 -1.626108 0)
			(unlocked yes)
			(layer "F.SilkS")
			(effects
				(font
					(size 1.905 1.4224)
					(thickness 0.1524)
				)
				(justify left)
			)
		)
		(fp_text user "+"
			(at -4.619244 1.084072 180)
			(unlocked yes)
			(layer "F.SilkS")
			(effects
				(font
					(size 1.905 1.4224)
					(thickness 0.1524)
				)
				(justify left)
			)
		)
		(fp_text user "-"
			(at 5.4102 0.29845 0)
			(unlocked yes)
			(layer "F.Fab")
			(effects
				(font
					(size 1.905 1.4224)
					(thickness 0.1524)
				)
				(justify left)
			)
		)
		(fp_text user "+"
			(at -4.7752 -0.12065 180)
			(unlocked yes)
			(layer "F.Fab")
			(effects
				(font
					(size 1.905 1.4224)
					(thickness 0.1524)
				)
				(justify left)
			)
		)
		(pad "A" smd rect
			(at -1.999996 0 270)
			(size 1.7018 2.5146)
			(layers "F.Cu" "F.Mask" "F.Paste")
			(net "GND")
		)
		(pad "C" smd rect
			(at 1.999996 0 270)
			(size 1.7018 2.5146)
			(layers "F.Cu" "F.Mask" "F.Paste")
			(net "P12V_NIC5_R")
		)
	)
	(footprint ""
		(layer "F.Cu")
		(at 404.18004 -138.6332 180)
		(property "Reference" "R347"
			(at 0 0 180)
			(layer "F.SilkS")
			(hide yes)
			(effects
				(font
					(size 1.27 1.27)
				)
			)
		)
		(property "Value" ""
			(at 0 0 180)
			(layer "F.Fab")
			(effects
				(font
					(size 1.27 1.27)
				)
			)
		)
		(duplicate_pad_numbers_are_jumpers no)
		(fp_line
			(start 0.7874 0.4064)
			(end -0.7874 0.4064)
			(stroke
				(width 0.1524)
				(type default)
			)
			(layer "F.SilkS")
		)
		(fp_line
			(start 0.7874 -0.4064)
			(end 0.7874 0.4064)
			(stroke
				(width 0.1524)
				(type default)
			)
			(layer "F.SilkS")
		)
		(fp_line
			(start -0.7874 0.4064)
			(end -0.7874 -0.4064)
			(stroke
				(width 0.1524)
				(type default)
			)
			(layer "F.SilkS")
		)
		(fp_line
			(start -0.7874 -0.4064)
			(end 0.7874 -0.4064)
			(stroke
				(width 0.1524)
				(type default)
			)
			(layer "F.SilkS")
		)
		(fp_line
			(start 0.67945 0.3048)
			(end 0.120396 0.3048)
			(stroke
				(width 0.1)
				(type default)
			)
			(layer "F.Fab")
		)
		(fp_line
			(start 0.67945 -0.3048)
			(end 0.67945 0.3048)
			(stroke
				(width 0.1)
				(type default)
			)
			(layer "F.Fab")
		)
		(fp_line
			(start 0.12065 -0.2794)
			(end 0.12065 -0.3048)
			(stroke
				(width 0.1)
				(type default)
			)
			(layer "F.Fab")
		)
		(fp_line
			(start 0.12065 -0.3048)
			(end 0.67945 -0.3048)
			(stroke
				(width 0.1)
				(type default)
			)
			(layer "F.Fab")
		)
		(fp_line
			(start 0.120396 0.3048)
			(end 0.120396 0.2794)
			(stroke
				(width 0.1)
				(type default)
			)
			(layer "F.Fab")
		)
		(fp_line
			(start 0.120396 0.2794)
			(end -0.12065 0.2794)
			(stroke
				(width 0.1)
				(type default)
			)
			(layer "F.Fab")
		)
		(fp_line
			(start -0.12065 0.3048)
			(end -0.67945 0.3048)
			(stroke
				(width 0.1)
				(type default)
			)
			(layer "F.Fab")
		)
		(fp_line
			(start -0.12065 0.2794)
			(end -0.12065 0.3048)
			(stroke
				(width 0.1)
				(type default)
			)
			(layer "F.Fab")
		)
		(fp_line
			(start -0.12065 -0.2794)
			(end 0.12065 -0.2794)
			(stroke
				(width 0.1)
				(type default)
			)
			(layer "F.Fab")
		)
		(fp_line
			(start -0.12065 -0.305054)
			(end -0.12065 -0.2794)
			(stroke
				(width 0.1)
				(type default)
			)
			(layer "F.Fab")
		)
		(fp_line
			(start -0.67945 0.3048)
			(end -0.67945 -0.305054)
			(stroke
				(width 0.1)
				(type default)
			)
			(layer "F.Fab")
		)
		(fp_line
			(start -0.67945 -0.305054)
			(end -0.12065 -0.305054)
			(stroke
				(width 0.1)
				(type default)
			)
			(layer "F.Fab")
		)
		(pad "1" smd circle
			(at -0.40005 0 180)
			(size 0 0)
			(layers "F.Cu" "F.Mask" "F.Paste")
			(net "PRSNT_NIC6_N")
		)
		(pad "2" smd circle
			(at 0.40005 0 180)
			(size 0 0)
			(layers "F.Cu" "F.Mask" "F.Paste")
			(net "PRSNTB2_NIC6_N")
		)
	)
)
